(kicad_pcb
	(version 20241229)
	(generator "pcbnew")
	(generator_version "9.0")
	(general
		(thickness 1.294)
		(legacy_teardrops no)
	)
	(paper "A3")
	(title_block
		(title "Kintex 410T devboard")
		(date "2024-04-03")
		(rev "1.1.2")
		(comment 9 "footprints 603-608 of 975")
	)
	(layers
		(0 "F.Cu" mixed)
		(4 "In1.Cu" power)
		(6 "In2.Cu" power)
		(8 "In3.Cu" mixed)
		(10 "In4.Cu" power)
		(12 "In5.Cu" mixed)
		(14 "In6.Cu" power)
		(16 "In7.Cu" mixed)
		(18 "In8.Cu" power)
		(2 "B.Cu" mixed)
		(9 "F.Adhes" user "F.Adhesive")
		(11 "B.Adhes" user "B.Adhesive")
		(13 "F.Paste" user)
		(15 "B.Paste" user)
		(5 "F.SilkS" user "F.Silkscreen")
		(7 "B.SilkS" user "B.Silkscreen")
		(1 "F.Mask" user)
		(3 "B.Mask" user)
		(17 "Dwgs.User" user "User.Drawings")
		(19 "Cmts.User" user "User.Comments")
		(21 "Eco1.User" user "User.Eco1")
		(23 "Eco2.User" user "User.Eco2")
		(25 "Edge.Cuts" user)
		(27 "Margin" user)
		(31 "F.CrtYd" user "F.Courtyard")
		(29 "B.CrtYd" user "B.Courtyard")
		(35 "F.Fab" user)
		(33 "B.Fab" user)
	)
	(footprint "antmicro-footprints:R_0402_1005Metric"
		(layer "B.Cu")
		(at 265.901 146.85)
		(descr "Resistor SMD 0402")
		(tags "resistor SMD 0402")
		(property "Reference" "R59"
			(at -3.851 0.325 180)
			(layer "B.SilkS")
			(effects
				(font
					(size 0.7 0.7)
					(thickness 0.15)
				)
				(justify left bottom mirror)
			)
		)
		(property "Value" "R_1k_0402"
			(at 0 -1.4 180)
			(layer "B.Fab")
			(effects
				(font
					(size 0.7 0.7)
					(thickness 0.15)
				)
				(justify left bottom mirror)
			)
		)
		(property "Description" "SMD Chip Resistor, 1 kohm, ± 1%, 63 mW, 0402 [1005 Metric], Thick Film, General Purpose"
			(at 0 0 0)
			(layer "F.Fab")
			(hide yes)
			(effects
				(font
					(size 1.27 1.27)
					(thickness 0.15)
				)
			)
		)
		(property "Author" "Antmicro"
			(at 0 0 0)
			(layer "B.Fab")
			(hide yes)
			(effects
				(font
					(size 1 1)
					(thickness 0.15)
				)
				(justify mirror)
			)
		)
		(property "License" "Apache-2.0"
			(at 0 0 0)
			(layer "B.Fab")
			(hide yes)
			(effects
				(font
					(size 1 1)
					(thickness 0.15)
				)
				(justify mirror)
			)
		)
		(property "MPN" "CR0402-FX-1001GLF"
			(at 0 0 0)
			(layer "B.Fab")
			(hide yes)
			(effects
				(font
					(size 1 1)
					(thickness 0.15)
				)
				(justify mirror)
			)
		)
		(property "Manufacturer" "Bourns"
			(at 0 0 0)
			(layer "B.Fab")
			(hide yes)
			(effects
				(font
					(size 1 1)
					(thickness 0.15)
				)
				(justify mirror)
			)
		)
		(property "Tolerance" "1%"
			(at 0 0 0)
			(layer "B.Fab")
			(hide yes)
			(effects
				(font
					(size 1 1)
					(thickness 0.15)
				)
				(justify mirror)
			)
		)
		(property "Val" "1k"
			(at 0 0 0)
			(layer "B.Fab")
			(hide yes)
			(effects
				(font
					(size 1 1)
					(thickness 0.15)
				)
				(justify mirror)
			)
		)
		(sheetname "Power supply")
		(sheetfile "power-supply.kicad_sch")
		(attr smd)
		(fp_rect
			(start -0.925 0.47)
			(end 0.925 -0.47)
			(stroke
				(width 0.05)
				(type default)
			)
			(fill no)
			(layer "B.CrtYd")
		)
		(fp_rect
			(start -0.5 0.25)
			(end 0.5 -0.25)
			(stroke
				(width 0.15)
				(type solid)
			)
			(fill no)
			(layer "B.Fab")
		)
		(pad "1" smd roundrect
			(at -0.48 0)
			(size 0.59 0.64)
			(layers "B.Cu" "B.Mask" "B.Paste")
			(roundrect_rratio 0.25)
			(net 24 "+3V3")
			(pintype "passive")
		)
		(pad "2" smd roundrect
			(at 0.48 0)
			(size 0.59 0.64)
			(layers "B.Cu" "B.Mask" "B.Paste")
			(roundrect_rratio 0.25)
			(net 755 "Net-(D12-A)")
			(pintype "passive")
		)
	)
	(footprint "antmicro-footprints:C_0402_1005Metric"
		(layer "B.Cu")
		(at 194.5 122 90)
		(descr "Capacitor SMD 0402")
		(tags "capacitor SMD 0402")
		(property "Reference" "C76"
			(at 31.125 23.5 270)
			(layer "B.SilkS")
			(effects
				(font
					(size 0.7 0.7)
					(thickness 0.15)
				)
				(justify left bottom mirror)
			)
		)
		(property "Value" "C_100n_0402"
			(at 0 -1.169 270)
			(layer "B.Fab")
			(effects
				(font
					(size 0.7 0.7)
					(thickness 0.15)
				)
				(justify left bottom mirror)
			)
		)
		(property "Description" "SMD Multilayer Ceramic Capacitor, 0.1 µF, 50 V, 0402 [1005 Metric], ± 10%, X5R, GRM Series"
			(at 0 0 90)
			(layer "F.Fab")
			(hide yes)
			(effects
				(font
					(size 1.27 1.27)
					(thickness 0.15)
				)
			)
		)
		(property "Author" "Antmicro"
			(at 316.5 -72.5 0)
			(layer "B.Fab")
			(hide yes)
			(effects
				(font
					(size 1 1)
					(thickness 0.15)
				)
				(justify mirror)
			)
		)
		(property "Dielectric" "X5R"
			(at 316.5 -72.5 0)
			(layer "B.Fab")
			(hide yes)
			(effects
				(font
					(size 1 1)
					(thickness 0.15)
				)
				(justify mirror)
			)
		)
		(property "License" "Apache-2.0"
			(at 316.5 -72.5 0)
			(layer "B.Fab")
			(hide yes)
			(effects
				(font
					(size 1 1)
					(thickness 0.15)
				)
				(justify mirror)
			)
		)
		(property "MPN" "GRM155R61H104KE14D"
			(at 316.5 -72.5 0)
			(layer "B.Fab")
			(hide yes)
			(effects
				(font
					(size 1 1)
					(thickness 0.15)
				)
				(justify mirror)
			)
		)
		(property "Manufacturer" "Murata"
			(at 316.5 -72.5 0)
			(layer "B.Fab")
			(hide yes)
			(effects
				(font
					(size 1 1)
					(thickness 0.15)
				)
				(justify mirror)
			)
		)
		(property "Val" "100n"
			(at 316.5 -72.5 0)
			(layer "B.Fab")
			(hide yes)
			(effects
				(font
					(size 1 1)
					(thickness 0.15)
				)
				(justify mirror)
			)
		)
		(property "Voltage" "50V"
			(at 316.5 -72.5 0)
			(layer "B.Fab")
			(hide yes)
			(effects
				(font
					(size 1 1)
					(thickness 0.15)
				)
				(justify mirror)
			)
		)
		(sheetname "FPGA Bank 18 & 32")
		(sheetfile "fpga-bank-18-32.kicad_sch")
		(attr smd)
		(fp_rect
			(start -0.925 0.47)
			(end 0.925 -0.47)
			(stroke
				(width 0.05)
				(type default)
			)
			(fill no)
			(layer "B.CrtYd")
		)
		(fp_line
			(start 0.504 -0.248)
			(end -0.494 -0.248)
			(stroke
				(width 0.15)
				(type solid)
			)
			(layer "B.Fab")
		)
		(fp_line
			(start -0.494 -0.248)
			(end -0.494 0.25)
			(stroke
				(width 0.15)
				(type solid)
			)
			(layer "B.Fab")
		)
		(fp_line
			(start 0.504 0.25)
			(end 0.504 -0.248)
			(stroke
				(width 0.15)
				(type solid)
			)
			(layer "B.Fab")
		)
		(fp_line
			(start -0.494 0.25)
			(end 0.504 0.25)
			(stroke
				(width 0.15)
				(type solid)
			)
			(layer "B.Fab")
		)
		(pad "1" smd roundrect
			(at -0.48 0 90)
			(size 0.59 0.64)
			(layers "B.Cu" "B.Mask" "B.Paste")
			(roundrect_rratio 0.25)
			(net 1 "GND")
			(pintype "passive")
		)
		(pad "2" smd roundrect
			(at 0.48 0 90)
			(size 0.59 0.64)
			(layers "B.Cu" "B.Mask" "B.Paste")
			(roundrect_rratio 0.25)
			(net 24 "+3V3")
			(pintype "passive")
		)
	)
	(footprint "antmicro-footprints:R_0402_1005Metric"
		(layer "B.Cu")
		(at 245.001 130.1 90)
		(descr "Resistor SMD 0402")
		(tags "resistor SMD 0402")
		(property "Reference" "R89"
			(at -0.8 0.374 270)
			(layer "B.SilkS")
			(effects
				(font
					(size 0.7 0.7)
					(thickness 0.15)
				)
				(justify left bottom mirror)
			)
		)
		(property "Value" "R_10k_0402"
			(at 0 -1.4 270)
			(layer "B.Fab")
			(effects
				(font
					(size 0.7 0.7)
					(thickness 0.15)
				)
				(justify left bottom mirror)
			)
		)
		(property "Description" "SMD Chip Resistor, 10 kohm, ± 1%, 62.5 mW, 0402 [1005 Metric], Thick Film, General Purpose"
			(at 0 0 90)
			(layer "F.Fab")
			(hide yes)
			(effects
				(font
					(size 1.27 1.27)
					(thickness 0.15)
				)
			)
		)
		(property "Author" "Antmicro"
			(at 375.101 -114.901 0)
			(layer "B.Fab")
			(hide yes)
			(effects
				(font
					(size 1 1)
					(thickness 0.15)
				)
				(justify mirror)
			)
		)
		(property "License" "Apache-2.0"
			(at 375.101 -114.901 0)
			(layer "B.Fab")
			(hide yes)
			(effects
				(font
					(size 1 1)
					(thickness 0.15)
				)
				(justify mirror)
			)
		)
		(property "MPN" "CR0402-FX-1002GLF"
			(at 375.101 -114.901 0)
			(layer "B.Fab")
			(hide yes)
			(effects
				(font
					(size 1 1)
					(thickness 0.15)
				)
				(justify mirror)
			)
		)
		(property "Manufacturer" "Bourns"
			(at 375.101 -114.901 0)
			(layer "B.Fab")
			(hide yes)
			(effects
				(font
					(size 1 1)
					(thickness 0.15)
				)
				(justify mirror)
			)
		)
		(property "Tolerance" "1%"
			(at 375.101 -114.901 0)
			(layer "B.Fab")
			(hide yes)
			(effects
				(font
					(size 1 1)
					(thickness 0.15)
				)
				(justify mirror)
			)
		)
		(property "Val" "10k"
			(at 375.101 -114.901 0)
			(layer "B.Fab")
			(hide yes)
			(effects
				(font
					(size 1 1)
					(thickness 0.15)
				)
				(justify mirror)
			)
		)
		(sheetname "SPI Flash + SD Card")
		(sheetfile "spi-flash.kicad_sch")
		(attr smd)
		(fp_rect
			(start -0.925 0.47)
			(end 0.925 -0.47)
			(stroke
				(width 0.05)
				(type default)
			)
			(fill no)
			(layer "B.CrtYd")
		)
		(fp_rect
			(start -0.5 0.25)
			(end 0.5 -0.25)
			(stroke
				(width 0.15)
				(type solid)
			)
			(fill no)
			(layer "B.Fab")
		)
		(pad "1" smd roundrect
			(at -0.48 0 90)
			(size 0.59 0.64)
			(layers "B.Cu" "B.Mask" "B.Paste")
			(roundrect_rratio 0.25)
			(net 394 "/FPGA Bank 33 & 34/SD_CARD.CLK")
			(pintype "passive")
		)
		(pad "2" smd roundrect
			(at 0.48 0 90)
			(size 0.59 0.64)
			(layers "B.Cu" "B.Mask" "B.Paste")
			(roundrect_rratio 0.25)
			(net 24 "+3V3")
			(pintype "passive")
		)
	)
	(footprint "antmicro-footprints:C_0201"
		(layer "B.Cu")
		(at 201.5 127.25 180)
		(descr "Capacitor SMD 0201")
		(tags "capacitor SMD 0201")
		(property "Reference" "C74"
			(at -26.925 29.35 0)
			(layer "B.SilkS")
			(effects
				(font
					(size 0.7 0.7)
					(thickness 0.15)
				)
				(justify left bottom mirror)
			)
		)
		(property "Value" "C_100n_0201"
			(at 0 -1.4 0)
			(layer "B.Fab")
			(effects
				(font
					(size 0.7 0.7)
					(thickness 0.15)
				)
				(justify left bottom mirror)
			)
		)
		(property "Description" "SMD Multilayer Ceramic Capacitor, 0.1 µF, 6.3 V, 0201 [0603 Metric], ± 10%, X6S, CC Series"
			(at 0 0 180)
			(layer "F.Fab")
			(hide yes)
			(effects
				(font
					(size 1.27 1.27)
					(thickness 0.15)
				)
			)
		)
		(property "Author" "Antmicro"
			(at 403 254.5 0)
			(layer "B.Fab")
			(hide yes)
			(effects
				(font
					(size 1 1)
					(thickness 0.15)
				)
				(justify mirror)
			)
		)
		(property "Dielectric" ""
			(at 403 254.5 0)
			(layer "B.Fab")
			(hide yes)
			(effects
				(font
					(size 1 1)
					(thickness 0.15)
				)
				(justify mirror)
			)
		)
		(property "License" "Apache-2.0"
			(at 403 254.5 0)
			(layer "B.Fab")
			(hide yes)
			(effects
				(font
					(size 1 1)
					(thickness 0.15)
				)
				(justify mirror)
			)
		)
		(property "MPN" "CC0201KRX6S5BB104"
			(at 403 254.5 0)
			(layer "B.Fab")
			(hide yes)
			(effects
				(font
					(size 1 1)
					(thickness 0.15)
				)
				(justify mirror)
			)
		)
		(property "Manufacturer" "YAGEO"
			(at 403 254.5 0)
			(layer "B.Fab")
			(hide yes)
			(effects
				(font
					(size 1 1)
					(thickness 0.15)
				)
				(justify mirror)
			)
		)
		(property "Val" "100n"
			(at 403 254.5 0)
			(layer "B.Fab")
			(hide yes)
			(effects
				(font
					(size 1 1)
					(thickness 0.15)
				)
				(justify mirror)
			)
		)
		(property "Voltage" ""
			(at 403 254.5 0)
			(layer "B.Fab")
			(hide yes)
			(effects
				(font
					(size 1 1)
					(thickness 0.15)
				)
				(justify mirror)
			)
		)
		(sheetname "FPGA supply")
		(sheetfile "fpga-supply.kicad_sch")
		(attr smd)
		(fp_rect
			(start -0.7 0.35)
			(end 0.7 -0.35)
			(stroke
				(width 0.05)
				(type default)
			)
			(fill no)
			(layer "B.CrtYd")
		)
		(fp_rect
			(start 0.3 -0.15)
			(end -0.301 0.149)
			(stroke
				(width 0.15)
				(type solid)
			)
			(fill no)
			(layer "B.Fab")
		)
		(pad "" smd roundrect
			(at -0.349 0.002 180)
			(size 0.318 0.36)
			(layers "B.Paste")
			(roundrect_rratio 0.25)
		)
		(pad "" smd roundrect
			(at 0.341 0.002 180)
			(size 0.318 0.36)
			(layers "B.Paste")
			(roundrect_rratio 0.25)
		)
		(pad "1" smd roundrect
			(at -0.321 0.002 180)
			(size 0.46 0.4)
			(layers "B.Cu" "B.Mask")
			(roundrect_rratio 0.25)
			(net 1 "GND")
			(pintype "passive")
		)
		(pad "2" smd roundrect
			(at 0.32 0.002 180)
			(size 0.46 0.4)
			(layers "B.Cu" "B.Mask")
			(roundrect_rratio 0.25)
			(net 650 "+1V0")
			(pintype "passive")
		)
	)
	(footprint "antmicro-footprints:C_0201"
		(layer "B.Cu")
		(at 202.65 128.5 -90)
		(descr "Capacitor SMD 0201")
		(tags "capacitor SMD 0201")
		(property "Reference" "C137"
			(at -30.475 -26.975 90)
			(layer "B.SilkS")
			(effects
				(font
					(size 0.7 0.7)
					(thickness 0.15)
				)
				(justify left bottom mirror)
			)
		)
		(property "Value" "C_100n_0201"
			(at 0 -1.4 90)
			(layer "B.Fab")
			(effects
				(font
					(size 0.7 0.7)
					(thickness 0.15)
				)
				(justify left bottom mirror)
			)
		)
		(property "Description" "SMD Multilayer Ceramic Capacitor, 0.1 µF, 6.3 V, 0201 [0603 Metric], ± 10%, X6S, CC Series"
			(at 0 0 270)
			(layer "F.Fab")
			(hide yes)
			(effects
				(font
					(size 1.27 1.27)
					(thickness 0.15)
				)
			)
		)
		(property "Author" "Antmicro"
			(at 74.15 331.15 0)
			(layer "B.Fab")
			(hide yes)
			(effects
				(font
					(size 1 1)
					(thickness 0.15)
				)
				(justify mirror)
			)
		)
		(property "Dielectric" ""
			(at 74.15 331.15 0)
			(layer "B.Fab")
			(hide yes)
			(effects
				(font
					(size 1 1)
					(thickness 0.15)
				)
				(justify mirror)
			)
		)
		(property "License" "Apache-2.0"
			(at 74.15 331.15 0)
			(layer "B.Fab")
			(hide yes)
			(effects
				(font
					(size 1 1)
					(thickness 0.15)
				)
				(justify mirror)
			)
		)
		(property "MPN" "CC0201KRX6S5BB104"
			(at 74.15 331.15 0)
			(layer "B.Fab")
			(hide yes)
			(effects
				(font
					(size 1 1)
					(thickness 0.15)
				)
				(justify mirror)
			)
		)
		(property "Manufacturer" "YAGEO"
			(at 74.15 331.15 0)
			(layer "B.Fab")
			(hide yes)
			(effects
				(font
					(size 1 1)
					(thickness 0.15)
				)
				(justify mirror)
			)
		)
		(property "Val" "100n"
			(at 74.15 331.15 0)
			(layer "B.Fab")
			(hide yes)
			(effects
				(font
					(size 1 1)
					(thickness 0.15)
				)
				(justify mirror)
			)
		)
		(property "Voltage" ""
			(at 74.15 331.15 0)
			(layer "B.Fab")
			(hide yes)
			(effects
				(font
					(size 1 1)
					(thickness 0.15)
				)
				(justify mirror)
			)
		)
		(sheetname "FPGA supply")
		(sheetfile "fpga-supply.kicad_sch")
		(attr smd)
		(fp_rect
			(start -0.7 0.35)
			(end 0.7 -0.35)
			(stroke
				(width 0.05)
				(type default)
			)
			(fill no)
			(layer "B.CrtYd")
		)
		(fp_rect
			(start 0.3 -0.15)
			(end -0.301 0.149)
			(stroke
				(width 0.15)
				(type solid)
			)
			(fill no)
			(layer "B.Fab")
		)
		(pad "" smd roundrect
			(at -0.349 0.002 270)
			(size 0.318 0.36)
			(layers "B.Paste")
			(roundrect_rratio 0.25)
		)
		(pad "" smd roundrect
			(at 0.341 0.002 270)
			(size 0.318 0.36)
			(layers "B.Paste")
			(roundrect_rratio 0.25)
		)
		(pad "1" smd roundrect
			(at -0.321 0.002 270)
			(size 0.46 0.4)
			(layers "B.Cu" "B.Mask")
			(roundrect_rratio 0.25)
			(net 1 "GND")
			(pintype "passive")
		)
		(pad "2" smd roundrect
			(at 0.32 0.002 270)
			(size 0.46 0.4)
			(layers "B.Cu" "B.Mask")
			(roundrect_rratio 0.25)
			(net 650 "+1V0")
			(pintype "passive")
		)
	)
	(footprint "antmicro-footprints:C_0201"
		(layer "B.Cu")
		(at 188.000001 124.500001 180)
		(descr "Capacitor SMD 0201")
		(tags "capacitor SMD 0201")
		(property "Reference" "C158"
			(at 0.700001 -0.349999 0)
			(layer "B.SilkS")
			(effects
				(font
					(size 0.7 0.7)
					(thickness 0.15)
				)
				(justify left bottom mirror)
			)
		)
		(property "Value" "C_100n_0201"
			(at 0 -1.4 0)
			(layer "B.Fab")
			(effects
				(font
					(size 0.7 0.7)
					(thickness 0.15)
				)
				(justify left bottom mirror)
			)
		)
		(property "Description" "SMD Multilayer Ceramic Capacitor, 0.1 µF, 6.3 V, 0201 [0603 Metric], ± 10%, X6S, CC Series"
			(at 0 0 180)
			(layer "F.Fab")
			(hide yes)
			(effects
				(font
					(size 1.27 1.27)
					(thickness 0.15)
				)
			)
		)
		(property "Author" "Antmicro"
			(at 376.000002 249.000002 0)
			(layer "B.Fab")
			(hide yes)
			(effects
				(font
					(size 1 1)
					(thickness 0.15)
				)
				(justify mirror)
			)
		)
		(property "Dielectric" ""
			(at 376.000002 249.000002 0)
			(layer "B.Fab")
			(hide yes)
			(effects
				(font
					(size 1 1)
					(thickness 0.15)
				)
				(justify mirror)
			)
		)
		(property "License" "Apache-2.0"
			(at 376.000002 249.000002 0)
			(layer "B.Fab")
			(hide yes)
			(effects
				(font
					(size 1 1)
					(thickness 0.15)
				)
				(justify mirror)
			)
		)
		(property "MPN" "CC0201KRX6S5BB104"
			(at 376.000002 249.000002 0)
			(layer "B.Fab")
			(hide yes)
			(effects
				(font
					(size 1 1)
					(thickness 0.15)
				)
				(justify mirror)
			)
		)
		(property "Manufacturer" "YAGEO"
			(at 376.000002 249.000002 0)
			(layer "B.Fab")
			(hide yes)
			(effects
				(font
					(size 1 1)
					(thickness 0.15)
				)
				(justify mirror)
			)
		)
		(property "Val" "100n"
			(at 376.000002 249.000002 0)
			(layer "B.Fab")
			(hide yes)
			(effects
				(font
					(size 1 1)
					(thickness 0.15)
				)
				(justify mirror)
			)
		)
		(property "Voltage" ""
			(at 376.000002 249.000002 0)
			(layer "B.Fab")
			(hide yes)
			(effects
				(font
					(size 1 1)
					(thickness 0.15)
				)
				(justify mirror)
			)
		)
		(sheetname "FPGA supply")
		(sheetfile "fpga-supply.kicad_sch")
		(attr smd)
		(fp_rect
			(start -0.7 0.35)
			(end 0.7 -0.35)
			(stroke
				(width 0.05)
				(type default)
			)
			(fill no)
			(layer "B.CrtYd")
		)
		(fp_rect
			(start 0.3 -0.15)
			(end -0.301 0.149)
			(stroke
				(width 0.15)
				(type solid)
			)
			(fill no)
			(layer "B.Fab")
		)
		(pad "" smd roundrect
			(at -0.349 0.002 180)
			(size 0.318 0.36)
			(layers "B.Paste")
			(roundrect_rratio 0.25)
		)
		(pad "" smd roundrect
			(at 0.341 0.002 180)
			(size 0.318 0.36)
			(layers "B.Paste")
			(roundrect_rratio 0.25)
		)
		(pad "1" smd roundrect
			(at -0.321 0.002 180)
			(size 0.46 0.4)
			(layers "B.Cu" "B.Mask")
			(roundrect_rratio 0.25)
			(net 1 "GND")
			(pintype "passive")
		)
		(pad "2" smd roundrect
			(at 0.32 0.002 180)
			(size 0.46 0.4)
			(layers "B.Cu" "B.Mask")
			(roundrect_rratio 0.25)
			(net 8 "+1V2_MGTAVTT")
			(pintype "passive")
		)
	)
)
